# T6G (Grand Teton) — schematic netlist excerpt (pin names and nets, part order shuffled) for the footprints in the layout excerpt that follows; sources: Cadence DE-HDL packaged netlist, KiCad conversion of 04192023_DAF0TMB3IC0_F0TG_MB_C_brd_V02_OCP.brd

C669  Q_CAP  10UF 6.3V 20% X6S  pkg C0402  page 301 : A = P1V8_CPU0_RT_1D ; B = GND
C8641  Q_CAP  1000PF 50V 5% EMPTY  pkg 0402  page 224 : A = PWRGD_PVDD11_S3_P1_R ; B = GND

(kicad_pcb
	(version 20260206)
	(generator "pcbnew")
	(generator_version "10.0")
	(general
		(thickness 1.6)
		(legacy_teardrops no)
	)
	(paper "A4")
	(title_block
		(title "04192023_DAF0TMB3IC0_F0TG_MB_C_brd_V02_OCP.brd")
		(comment 1 "Grand Teton / footprints 972-973 of 8354")
	)
	(layers
		(0 "F.Cu" signal "TOP")
		(4 "In1.Cu" signal "GND")
		(6 "In2.Cu" signal "IN1")
		(8 "In3.Cu" signal "GND1")
		(10 "In4.Cu" signal "IN2")
		(12 "In5.Cu" signal "GND2")
		(14 "In6.Cu" signal "IN3")
		(16 "In7.Cu" signal "GND3")
		(18 "In8.Cu" signal "VCC")
		(20 "In9.Cu" signal "VCC1")
		(22 "In10.Cu" signal "GND4")
		(24 "In11.Cu" signal "IN4")
		(26 "In12.Cu" signal "GND5")
		(28 "In13.Cu" signal "IN5")
		(30 "In14.Cu" signal "GND6")
		(32 "In15.Cu" signal "IN6")
		(34 "In16.Cu" signal "GND7")
		(2 "B.Cu" signal "BOTTOM")
		(9 "F.Adhes" user "F.Adhesive")
		(11 "B.Adhes" user "B.Adhesive")
		(13 "F.Paste" user "Package Geometry/Pastemask Top")
		(15 "B.Paste" user "Package Geometry/Pastemask Bottom")
		(5 "F.SilkS" user "Ref Des/Silkscreen Top")
		(7 "B.SilkS" user "Ref Des/Silkscreen Bottom")
		(1 "F.Mask" user "Board Geometry/Soldermask Top")
		(3 "B.Mask" user "Board Geometry/Soldermask Bottom")
		(17 "Dwgs.User" user "User.Drawings")
		(19 "Cmts.User" user "User.Comments")
		(21 "Eco1.User" user "User.Eco1")
		(23 "Eco2.User" user "User.Eco2")
		(25 "Edge.Cuts" user "Board Geometry/Outline")
		(27 "Margin" user)
		(31 "F.CrtYd" user "Package Geometry/Place Bound Top")
		(29 "B.CrtYd" user "Package Geometry/Place Bound Bottom")
		(35 "F.Fab" user "Ref Des/Assembly Top")
		(33 "B.Fab" user "Ref Des/Assembly Bottom")
	)
	(footprint ""
		(layer "F.Cu")
		(at 157.692852 -351.247456 180)
		(property "Reference" "C8641"
			(at 0 0 180)
			(layer "F.SilkS")
			(hide yes)
			(effects
				(font
					(size 1.27 1.27)
				)
			)
		)
		(property "Value" ""
			(at 0 0 180)
			(layer "F.Fab")
			(effects
				(font
					(size 1.27 1.27)
				)
			)
		)
		(duplicate_pad_numbers_are_jumpers no)
		(fp_line
			(start 0.7874 0.4064)
			(end -0.7874 0.4064)
			(stroke
				(width 0.1524)
				(type default)
			)
			(layer "F.SilkS")
		)
		(fp_line
			(start 0.7874 -0.4064)
			(end 0.7874 0.4064)
			(stroke
				(width 0.1524)
				(type default)
			)
			(layer "F.SilkS")
		)
		(fp_line
			(start -0.7874 0.4064)
			(end -0.7874 -0.4064)
			(stroke
				(width 0.1524)
				(type default)
			)
			(layer "F.SilkS")
		)
		(fp_line
			(start -0.7874 -0.4064)
			(end 0.7874 -0.4064)
			(stroke
				(width 0.1524)
				(type default)
			)
			(layer "F.SilkS")
		)
		(fp_line
			(start 0.67945 0.3048)
			(end 0.120396 0.3048)
			(stroke
				(width 0.1)
				(type default)
			)
			(layer "F.Fab")
		)
		(fp_line
			(start 0.67945 -0.3048)
			(end 0.67945 0.3048)
			(stroke
				(width 0.1)
				(type default)
			)
			(layer "F.Fab")
		)
		(fp_line
			(start 0.12065 -0.2794)
			(end 0.12065 -0.3048)
			(stroke
				(width 0.1)
				(type default)
			)
			(layer "F.Fab")
		)
		(fp_line
			(start 0.12065 -0.3048)
			(end 0.67945 -0.3048)
			(stroke
				(width 0.1)
				(type default)
			)
			(layer "F.Fab")
		)
		(fp_line
			(start 0.120396 0.3048)
			(end 0.120396 0.2794)
			(stroke
				(width 0.1)
				(type default)
			)
			(layer "F.Fab")
		)
		(fp_line
			(start 0.120396 0.2794)
			(end -0.12065 0.2794)
			(stroke
				(width 0.1)
				(type default)
			)
			(layer "F.Fab")
		)
		(fp_line
			(start -0.12065 0.3048)
			(end -0.67945 0.3048)
			(stroke
				(width 0.1)
				(type default)
			)
			(layer "F.Fab")
		)
		(fp_line
			(start -0.12065 0.2794)
			(end -0.12065 0.3048)
			(stroke
				(width 0.1)
				(type default)
			)
			(layer "F.Fab")
		)
		(fp_line
			(start -0.12065 -0.2794)
			(end 0.12065 -0.2794)
			(stroke
				(width 0.1)
				(type default)
			)
			(layer "F.Fab")
		)
		(fp_line
			(start -0.12065 -0.305054)
			(end -0.12065 -0.2794)
			(stroke
				(width 0.1)
				(type default)
			)
			(layer "F.Fab")
		)
		(fp_line
			(start -0.67945 0.3048)
			(end -0.67945 -0.305054)
			(stroke
				(width 0.1)
				(type default)
			)
			(layer "F.Fab")
		)
		(fp_line
			(start -0.67945 -0.305054)
			(end -0.12065 -0.305054)
			(stroke
				(width 0.1)
				(type default)
			)
			(layer "F.Fab")
		)
		(pad "1" smd circle
			(at -0.40005 0 180)
			(size 0 0)
			(layers "F.Cu" "F.Mask" "F.Paste")
			(net "PWRGD_PVDD11_S3_P1_R")
		)
		(pad "2" smd circle
			(at 0.40005 0 180)
			(size 0 0)
			(layers "F.Cu" "F.Mask" "F.Paste")
			(net "GND")
		)
	)
	(footprint ""
		(layer "F.Cu")
		(at 429.171354 -397.135604)
		(property "Reference" "C669"
			(at 0 0 0)
			(layer "F.SilkS")
			(hide yes)
			(effects
				(font
					(size 1.27 1.27)
				)
			)
		)
		(property "Value" ""
			(at 0 0 0)
			(layer "F.Fab")
			(effects
				(font
					(size 1.27 1.27)
				)
			)
		)
		(duplicate_pad_numbers_are_jumpers no)
		(fp_line
			(start -0.7874 -0.4064)
			(end 0.7874 -0.4064)
			(stroke
				(width 0.1524)
				(type default)
			)
			(layer "F.SilkS")
		)
		(fp_line
			(start -0.7874 0.4064)
			(end -0.7874 -0.4064)
			(stroke
				(width 0.1524)
				(type default)
			)
			(layer "F.SilkS")
		)
		(fp_line
			(start 0.7874 -0.4064)
			(end 0.7874 0.4064)
			(stroke
				(width 0.1524)
				(type default)
			)
			(layer "F.SilkS")
		)
		(fp_line
			(start 0.7874 0.4064)
			(end -0.7874 0.4064)
			(stroke
				(width 0.1524)
				(type default)
			)
			(layer "F.SilkS")
		)
		(fp_line
			(start -0.67945 -0.305054)
			(end -0.12065 -0.305054)
			(stroke
				(width 0.1)
				(type default)
			)
			(layer "F.Fab")
		)
		(fp_line
			(start -0.67945 0.3048)
			(end -0.67945 -0.305054)
			(stroke
				(width 0.1)
				(type default)
			)
			(layer "F.Fab")
		)
		(fp_line
			(start -0.12065 -0.305054)
			(end -0.12065 -0.2794)
			(stroke
				(width 0.1)
				(type default)
			)
			(layer "F.Fab")
		)
		(fp_line
			(start -0.12065 -0.2794)
			(end 0.12065 -0.2794)
			(stroke
				(width 0.1)
				(type default)
			)
			(layer "F.Fab")
		)
		(fp_line
			(start -0.12065 0.2794)
			(end -0.12065 0.3048)
			(stroke
				(width 0.1)
				(type default)
			)
			(layer "F.Fab")
		)
		(fp_line
			(start -0.12065 0.3048)
			(end -0.67945 0.3048)
			(stroke
				(width 0.1)
				(type default)
			)
			(layer "F.Fab")
		)
		(fp_line
			(start 0.120396 0.2794)
			(end -0.12065 0.2794)
			(stroke
				(width 0.1)
				(type default)
			)
			(layer "F.Fab")
		)
		(fp_line
			(start 0.120396 0.3048)
			(end 0.120396 0.2794)
			(stroke
				(width 0.1)
				(type default)
			)
			(layer "F.Fab")
		)
		(fp_line
			(start 0.12065 -0.3048)
			(end 0.67945 -0.3048)
			(stroke
				(width 0.1)
				(type default)
			)
			(layer "F.Fab")
		)
		(fp_line
			(start 0.12065 -0.2794)
			(end 0.12065 -0.3048)
			(stroke
				(width 0.1)
				(type default)
			)
			(layer "F.Fab")
		)
		(fp_line
			(start 0.67945 -0.3048)
			(end 0.67945 0.3048)
			(stroke
				(width 0.1)
				(type default)
			)
			(layer "F.Fab")
		)
		(fp_line
			(start 0.67945 0.3048)
			(end 0.120396 0.3048)
			(stroke
				(width 0.1)
				(type default)
			)
			(layer "F.Fab")
		)
		(pad "1" smd circle
			(at -0.40005 0)
			(size 0 0)
			(layers "F.Cu" "F.Mask" "F.Paste")
			(net "P1V8_CPU0_RT_1D")
		)
		(pad "2" smd circle
			(at 0.40005 0)
			(size 0 0)
			(layers "F.Cu" "F.Mask" "F.Paste")
			(net "GND")
		)
	)
)
